(kicad_pcb
	(version 20260206)
	(generator "pcbnew")
	(generator_version "10.0")
	(general
		(thickness 1.6)
		(legacy_teardrops no)
	)
	(paper "A4")
	(title_block
		(title "Bryce Canyon_R.DPB_16317-1_OCP.brd")
		(comment 1 "Bryce Canyon / footprints 649-654 of 2099")
	)
	(layers
		(0 "F.Cu" signal "TOP")
		(4 "In1.Cu" signal "L2GND")
		(6 "In2.Cu" signal "L3")
		(8 "In3.Cu" signal "L4VCC")
		(10 "In4.Cu" signal "L5VCC")
		(12 "In5.Cu" signal "L6")
		(14 "In6.Cu" signal "L7GND")
		(2 "B.Cu" signal "BOTTOM")
		(9 "F.Adhes" user "F.Adhesive")
		(11 "B.Adhes" user "B.Adhesive")
		(13 "F.Paste" user "Package Geometry/Pastemask Top")
		(15 "B.Paste" user "Package Geometry/Pastemask Bottom")
		(5 "F.SilkS" user "Ref Des/Silkscreen Top")
		(7 "B.SilkS" user "Ref Des/Silkscreen Bottom")
		(1 "F.Mask" user "Board Geometry/Soldermask Top")
		(3 "B.Mask" user "Board Geometry/Soldermask Bottom")
		(17 "Dwgs.User" user "User.Drawings")
		(19 "Cmts.User" user "User.Comments")
		(21 "Eco1.User" user "User.Eco1")
		(23 "Eco2.User" user "User.Eco2")
		(25 "Edge.Cuts" user "Board Geometry/Outline")
		(27 "Margin" user)
		(31 "F.CrtYd" user "Package Geometry/Place Bound Top")
		(29 "B.CrtYd" user "Package Geometry/Place Bound Bottom")
		(35 "F.Fab" user "Ref Des/Assembly Top")
		(33 "B.Fab" user "Ref Des/Assembly Bottom")
	)
	(footprint ""
		(layer "F.Cu")
		(at 412.877 -146.304)
		(property "Reference" "R557"
			(at 0 0 0)
			(layer "F.SilkS")
			(hide yes)
			(effects
				(font
					(size 1.27 1.27)
				)
			)
		)
		(property "Value" "220R3F-1-GP"
			(at -0.0254 -2.5146 0)
			(unlocked yes)
			(layer "F.Fab")
			(hide yes)
			(effects
				(font
					(size 1.016 1.016)
					(thickness 0.1524)
				)
			)
		)
		(property "Device Type" "R603H22"
			(at -0.0254 -4.0386 0)
			(unlocked yes)
			(layer "F.Fab")
			(hide yes)
			(effects
				(font
					(size 1.016 1.016)
					(thickness 0.1524)
				)
			)
		)
		(duplicate_pad_numbers_are_jumpers no)
		(fp_line
			(start -0.4826 0)
			(end -0.2032 0)
			(stroke
				(width 0.2032)
				(type default)
			)
			(layer "F.SilkS")
		)
		(fp_line
			(start 0.2032 0)
			(end 0.4826 0)
			(stroke
				(width 0.2032)
				(type default)
			)
			(layer "F.SilkS")
		)
		(fp_rect
			(start -0.5842 1.3335)
			(end 0.5842 -1.3335)
			(stroke
				(width 0)
				(type default)
			)
			(fill no)
			(layer "F.CrtYd")
		)
		(fp_rect
			(start -0.5842 1.3335)
			(end 0.5842 -1.3335)
			(stroke
				(width 0)
				(type default)
			)
			(fill no)
			(layer "F.Fab")
		)
		(pad "1" smd custom
			(at 0 -0.762)
			(size 0.2159 0.2159)
			(layers "F.Cu" "F.Mask" "F.Paste")
			(net "HDD_PRSNT_21")
			(options
				(clearance outline)
				(anchor circle)
			)
			(primitives
				(gr_poly
					(pts
						(arc
							(start -0.3302 -0.4318)
							(mid -0.402042 -0.402042)
							(end -0.4318 -0.3302)
						)
						(arc
							(start -0.4318 0.3302)
							(mid -0.402042 0.402042)
							(end -0.3302 0.4318)
						)
						(arc
							(start 0.3302 0.4318)
							(mid 0.402042 0.402042)
							(end 0.4318 0.3302)
						)
						(arc
							(start 0.4318 -0.3302)
							(mid 0.402042 -0.402042)
							(end 0.3302 -0.4318)
						)
					)
					(width 0)
					(fill yes)
				)
			)
		)
		(pad "2" smd custom
			(at 0 0.762)
			(size 0.2159 0.2159)
			(layers "F.Cu" "F.Mask" "F.Paste")
			(net "DRIVE_B_21_INS")
			(options
				(clearance outline)
				(anchor circle)
			)
			(primitives
				(gr_poly
					(pts
						(arc
							(start -0.3302 -0.4318)
							(mid -0.402042 -0.402042)
							(end -0.4318 -0.3302)
						)
						(arc
							(start -0.4318 0.3302)
							(mid -0.402042 0.402042)
							(end -0.3302 0.4318)
						)
						(arc
							(start 0.3302 0.4318)
							(mid 0.402042 0.402042)
							(end 0.4318 0.3302)
						)
						(arc
							(start 0.4318 -0.3302)
							(mid 0.402042 -0.402042)
							(end 0.3302 -0.4318)
						)
					)
					(width 0)
					(fill yes)
				)
			)
		)
	)
	(footprint ""
		(layer "F.Cu")
		(at 462.452212 -21.599906 -90)
		(property "Reference" "R867"
			(at 0 0 270)
			(layer "F.SilkS")
			(hide yes)
			(effects
				(font
					(size 1.27 1.27)
				)
			)
		)
		(property "Value" "4K7R2J-2-GP"
			(at 0.064008 -3.993896 270)
			(unlocked yes)
			(layer "F.Fab")
			(hide yes)
			(effects
				(font
					(size 1.016 1.016)
					(thickness 0.1524)
				)
			)
		)
		(property "Device Type" "R402H16"
			(at 0.064008 -5.517896 270)
			(unlocked yes)
			(layer "F.Fab")
			(hide yes)
			(effects
				(font
					(size 1.016 1.016)
					(thickness 0.1524)
				)
			)
		)
		(duplicate_pad_numbers_are_jumpers no)
		(fp_line
			(start -0.508 -0.9398)
			(end -0.508 0.9398)
			(stroke
				(width 0.1524)
				(type default)
			)
			(layer "F.SilkS")
		)
		(fp_line
			(start 0.508 -0.9398)
			(end -0.508 -0.9398)
			(stroke
				(width 0.1524)
				(type default)
			)
			(layer "F.SilkS")
		)
		(fp_rect
			(start -0.508 0.9398)
			(end 0.508 -0.9398)
			(stroke
				(width 0)
				(type default)
			)
			(fill no)
			(layer "F.CrtYd")
		)
		(fp_rect
			(start -0.508 0.9398)
			(end 0.508 -0.9398)
			(stroke
				(width 0)
				(type default)
			)
			(fill no)
			(layer "F.Fab")
		)
		(pad "1" smd custom
			(at 0 -0.4445 270)
			(size 0.1397 0.1397)
			(layers "F.Cu" "F.Mask" "F.Paste")
			(net "P12V_B")
			(options
				(clearance outline)
				(anchor circle)
			)
			(primitives
				(gr_poly
					(pts
						(arc
							(start -0.1778 -0.2794)
							(mid -0.249642 -0.249642)
							(end -0.2794 -0.1778)
						)
						(arc
							(start -0.2794 0.1778)
							(mid -0.249642 0.249642)
							(end -0.1778 0.2794)
						)
						(arc
							(start 0.1778 0.2794)
							(mid 0.249642 0.249642)
							(end 0.2794 0.1778)
						)
						(arc
							(start 0.2794 -0.1778)
							(mid 0.249642 -0.249642)
							(end 0.1778 -0.2794)
						)
					)
					(width 0)
					(fill yes)
				)
			)
		)
		(pad "2" smd custom
			(at 0 0.4445 270)
			(size 0.1397 0.1397)
			(layers "F.Cu" "F.Mask" "F.Paste")
			(net "SW_HDD_R34")
			(options
				(clearance outline)
				(anchor circle)
			)
			(primitives
				(gr_poly
					(pts
						(arc
							(start -0.1778 -0.2794)
							(mid -0.249642 -0.249642)
							(end -0.2794 -0.1778)
						)
						(arc
							(start -0.2794 0.1778)
							(mid -0.249642 0.249642)
							(end -0.1778 0.2794)
						)
						(arc
							(start 0.1778 0.2794)
							(mid 0.249642 0.249642)
							(end 0.2794 0.1778)
						)
						(arc
							(start 0.2794 -0.1778)
							(mid 0.249642 -0.249642)
							(end 0.1778 -0.2794)
						)
					)
					(width 0)
					(fill yes)
				)
			)
		)
	)
	(footprint ""
		(layer "F.Cu")
		(at 257.0226 -220.27642)
		(property "Reference" "U14"
			(at 0 0 0)
			(layer "F.SilkS")
			(hide yes)
			(effects
				(font
					(size 1.27 1.27)
				)
			)
		)
		(property "Value" "ADC128D818CIMTX-NOPB-1-GP"
			(at 0.127 -12.573 0)
			(unlocked yes)
			(layer "F.Fab")
			(hide yes)
			(effects
				(font
					(size 1.016 1.016)
					(thickness 0.1524)
				)
			)
		)
		(property "Device Type" "TSOIC16H48"
			(at 0.1016 -14.5796 0)
			(unlocked yes)
			(layer "F.Fab")
			(hide yes)
			(effects
				(font
					(size 1.016 1.016)
					(thickness 0.1524)
				)
			)
		)
		(duplicate_pad_numbers_are_jumpers no)
		(fp_line
			(start -3.0988 -1.778)
			(end -3.0988 1.778)
			(stroke
				(width 0.1524)
				(type default)
			)
			(layer "F.SilkS")
		)
		(fp_line
			(start -3.0988 -1.778)
			(end 2.3622 -1.778)
			(stroke
				(width 0.1524)
				(type default)
			)
			(layer "F.SilkS")
		)
		(fp_line
			(start -2.921 3.81)
			(end -2.921 1.778)
			(stroke
				(width 0.508)
				(type default)
			)
			(layer "F.SilkS")
		)
		(fp_line
			(start -2.54 0)
			(end -3.0988 -0.5588)
			(stroke
				(width 0.1524)
				(type default)
			)
			(layer "F.SilkS")
		)
		(fp_line
			(start -2.54 0)
			(end -3.0988 0.5588)
			(stroke
				(width 0.1524)
				(type default)
			)
			(layer "F.SilkS")
		)
		(fp_line
			(start 2.3622 -1.778)
			(end 2.3622 1.778)
			(stroke
				(width 0.1524)
				(type default)
			)
			(layer "F.SilkS")
		)
		(fp_line
			(start 2.3622 1.778)
			(end -2.921 1.778)
			(stroke
				(width 0.1524)
				(type default)
			)
			(layer "F.SilkS")
		)
		(fp_poly
			(pts
				(xy -2.4638 -1.778) (xy -2.4638 1.778) (xy 2.3622 1.778) (xy 2.3622 -1.778)
			)
			(stroke
				(width 0)
				(type default)
			)
			(fill yes)
			(layer "F.SilkS")
		)
		(fp_rect
			(start -3.175 4.064)
			(end 3.175 -4.064)
			(stroke
				(width 0)
				(type default)
			)
			(fill no)
			(layer "F.CrtYd")
		)
		(fp_poly
			(pts
				(xy -3.175 -4.064) (xy 3.175 -4.064) (xy 3.175 4.064) (xy -3.175 4.064)
			)
			(stroke
				(width 0)
				(type default)
			)
			(fill no)
			(layer "F.Fab")
		)
		(pad "1" smd rect
			(at -2.27584 2.8194)
			(size 0.3556 1.524)
			(layers "F.Cu" "F.Mask" "F.Paste")
			(net "Net_266")
		)
		(pad "2" smd rect
			(at -1.6256 2.8194)
			(size 0.3556 1.524)
			(layers "F.Cu" "F.Mask" "F.Paste")
			(net "VOL_SEN_SDA")
		)
		(pad "3" smd rect
			(at -0.97536 2.8194)
			(size 0.3556 1.524)
			(layers "F.Cu" "F.Mask" "F.Paste")
			(net "VOL_SEN_SCL")
		)
		(pad "4" smd rect
			(at -0.32512 2.8194)
			(size 0.3556 1.524)
			(layers "F.Cu" "F.Mask" "F.Paste")
			(net "GND")
		)
		(pad "5" smd rect
			(at 0.32512 2.8194)
			(size 0.3556 1.524)
			(layers "F.Cu" "F.Mask" "F.Paste")
			(net "P3V3_STBY_B")
		)
		(pad "6" smd rect
			(at 0.97536 2.8194)
			(size 0.3556 1.524)
			(layers "F.Cu" "F.Mask" "F.Paste")
			(net "VOL_SEN_INT_N")
		)
		(pad "7" smd rect
			(at 1.6256 2.8194)
			(size 0.3556 1.524)
			(layers "F.Cu" "F.Mask" "F.Paste")
			(net "VOL_SEN_ADDR0")
		)
		(pad "8" smd rect
			(at 2.27584 2.8194)
			(size 0.3556 1.524)
			(layers "F.Cu" "F.Mask" "F.Paste")
			(net "VOL_SEN_ADDR0")
		)
		(pad "9" smd rect
			(at 2.27584 -2.8194)
			(size 0.3556 1.524)
			(layers "F.Cu" "F.Mask" "F.Paste")
			(net "Net_267")
		)
		(pad "10" smd rect
			(at 1.6256 -2.8194)
			(size 0.3556 1.524)
			(layers "F.Cu" "F.Mask" "F.Paste")
			(net "Net_268")
		)
		(pad "11" smd rect
			(at 0.97536 -2.8194)
			(size 0.3556 1.524)
			(layers "F.Cu" "F.Mask" "F.Paste")
			(net "Net_269")
		)
		(pad "12" smd rect
			(at 0.32512 -2.8194)
			(size 0.3556 1.524)
			(layers "F.Cu" "F.Mask" "F.Paste")
			(net "P5V_B_4_SENSE")
		)
		(pad "13" smd rect
			(at -0.32512 -2.8194)
			(size 0.3556 1.524)
			(layers "F.Cu" "F.Mask" "F.Paste")
			(net "P5V_B_3_SENSE")
		)
		(pad "14" smd rect
			(at -0.97536 -2.8194)
			(size 0.3556 1.524)
			(layers "F.Cu" "F.Mask" "F.Paste")
			(net "P5V_B_2_SENSE")
		)
		(pad "15" smd rect
			(at -1.6256 -2.8194)
			(size 0.3556 1.524)
			(layers "F.Cu" "F.Mask" "F.Paste")
			(net "P5V_B_1_SENSE")
		)
		(pad "16" smd rect
			(at -2.27584 -2.8194)
			(size 0.3556 1.524)
			(layers "F.Cu" "F.Mask" "F.Paste")
			(net "P3V3_SENSE")
		)
	)
	(footprint ""
		(layer "F.Cu")
		(at 318.262 -32.8676 180)
		(property "Reference" "R764"
			(at 0 0 180)
			(layer "F.SilkS")
			(hide yes)
			(effects
				(font
					(size 1.27 1.27)
				)
			)
		)
		(property "Value" "220R3F-1-GP"
			(at -0.0254 -2.5146 180)
			(unlocked yes)
			(layer "F.Fab")
			(hide yes)
			(effects
				(font
					(size 1.016 1.016)
					(thickness 0.1524)
				)
			)
		)
		(property "Device Type" "R603H22"
			(at -0.0254 -4.0386 180)
			(unlocked yes)
			(layer "F.Fab")
			(hide yes)
			(effects
				(font
					(size 1.016 1.016)
					(thickness 0.1524)
				)
			)
		)
		(duplicate_pad_numbers_are_jumpers no)
		(fp_line
			(start 0.2032 0)
			(end 0.4826 0)
			(stroke
				(width 0.2032)
				(type default)
			)
			(layer "F.SilkS")
		)
		(fp_line
			(start -0.4826 0)
			(end -0.2032 0)
			(stroke
				(width 0.2032)
				(type default)
			)
			(layer "F.SilkS")
		)
		(fp_rect
			(start -0.5842 1.3335)
			(end 0.5842 -1.3335)
			(stroke
				(width 0)
				(type default)
			)
			(fill no)
			(layer "F.CrtYd")
		)
		(fp_rect
			(start -0.5842 1.3335)
			(end 0.5842 -1.3335)
			(stroke
				(width 0)
				(type default)
			)
			(fill no)
			(layer "F.Fab")
		)
		(pad "1" smd custom
			(at 0 -0.762 180)
			(size 0.2159 0.2159)
			(layers "F.Cu" "F.Mask" "F.Paste")
			(net "HDD_PRSNT_30")
			(options
				(clearance outline)
				(anchor circle)
			)
			(primitives
				(gr_poly
					(pts
						(arc
							(start -0.3302 -0.4318)
							(mid -0.402042 -0.402042)
							(end -0.4318 -0.3302)
						)
						(arc
							(start -0.4318 0.3302)
							(mid -0.402042 0.402042)
							(end -0.3302 0.4318)
						)
						(arc
							(start 0.3302 0.4318)
							(mid 0.402042 0.402042)
							(end 0.4318 0.3302)
						)
						(arc
							(start 0.4318 -0.3302)
							(mid 0.402042 -0.402042)
							(end 0.3302 -0.4318)
						)
					)
					(width 0)
					(fill yes)
				)
			)
		)
		(pad "2" smd custom
			(at 0 0.762 180)
			(size 0.2159 0.2159)
			(layers "F.Cu" "F.Mask" "F.Paste")
			(net "DRIVE_B_30_INS")
			(options
				(clearance outline)
				(anchor circle)
			)
			(primitives
				(gr_poly
					(pts
						(arc
							(start -0.3302 -0.4318)
							(mid -0.402042 -0.402042)
							(end -0.4318 -0.3302)
						)
						(arc
							(start -0.4318 0.3302)
							(mid -0.402042 0.402042)
							(end -0.3302 0.4318)
						)
						(arc
							(start 0.3302 0.4318)
							(mid 0.402042 0.402042)
							(end 0.4318 0.3302)
						)
						(arc
							(start 0.4318 -0.3302)
							(mid 0.402042 -0.402042)
							(end 0.3302 -0.4318)
						)
					)
					(width 0)
					(fill yes)
				)
			)
		)
	)
	(footprint ""
		(layer "F.Cu")
		(at 172.593 -140.462 90)
		(property "Reference" "C260"
			(at 0 0 90)
			(layer "F.SilkS")
			(hide yes)
			(effects
				(font
					(size 1.27 1.27)
				)
			)
		)
		(property "Value" "SCD033U25V2KX-GP"
			(at 1.1811 -2.7051 90)
			(unlocked yes)
			(layer "F.Fab")
			(hide yes)
			(effects
				(font
					(size 1.016 1.016)
					(thickness 0.1524)
				)
			)
		)
		(property "Device Type" "C402H22"
			(at 1.1811 -4.2291 90)
			(unlocked yes)
			(layer "F.Fab")
			(hide yes)
			(effects
				(font
					(size 1.016 1.016)
					(thickness 0.1524)
				)
			)
		)
		(duplicate_pad_numbers_are_jumpers no)
		(fp_rect
			(start -0.4318 0.9525)
			(end 0.4318 -0.9525)
			(stroke
				(width 0)
				(type default)
			)
			(fill no)
			(layer "F.CrtYd")
		)
		(fp_rect
			(start -0.4318 0.9525)
			(end 0.4318 -0.9525)
			(stroke
				(width 0)
				(type default)
			)
			(fill no)
			(layer "F.Fab")
		)
		(pad "1" smd custom
			(at 0 -0.4445 90)
			(size 0.1524 0.1524)
			(layers "F.Cu" "F.Mask" "F.Paste")
			(net "P12V_B")
			(options
				(clearance outline)
				(anchor circle)
			)
			(primitives
				(gr_poly
					(pts
						(arc
							(start 0.3048 -0.2032)
							(mid 0.275042 -0.275042)
							(end 0.2032 -0.3048)
						)
						(arc
							(start -0.2032 -0.3048)
							(mid -0.275042 -0.275042)
							(end -0.3048 -0.2032)
						)
						(arc
							(start -0.3048 0.2032)
							(mid -0.275042 0.275042)
							(end -0.2032 0.3048)
						)
						(arc
							(start 0.2032 0.3048)
							(mid 0.275042 0.275042)
							(end 0.3048 0.2032)
						)
					)
					(width 0)
					(fill yes)
				)
			)
		)
		(pad "2" smd custom
			(at 0 0.4445 90)
			(size 0.1524 0.1524)
			(layers "F.Cu" "F.Mask" "F.Paste")
			(net "SW_HDD_N17")
			(options
				(clearance outline)
				(anchor circle)
			)
			(primitives
				(gr_poly
					(pts
						(arc
							(start 0.3048 -0.2032)
							(mid 0.275042 -0.275042)
							(end 0.2032 -0.3048)
						)
						(arc
							(start -0.2032 -0.3048)
							(mid -0.275042 -0.275042)
							(end -0.3048 -0.2032)
						)
						(arc
							(start -0.3048 0.2032)
							(mid -0.275042 0.275042)
							(end -0.2032 0.3048)
						)
						(arc
							(start 0.2032 0.3048)
							(mid 0.275042 0.275042)
							(end 0.3048 0.2032)
						)
					)
					(width 0)
					(fill yes)
				)
			)
		)
	)
	(footprint ""
		(layer "F.Cu")
		(at 447.9544 -31.6484)
		(property "Reference" "C474"
			(at 0 0 0)
			(layer "F.SilkS")
			(hide yes)
			(effects
				(font
					(size 1.27 1.27)
				)
			)
		)
		(property "Value" "SCD01U50V2KX-1GP"
			(at 1.1811 -2.7051 0)
			(unlocked yes)
			(layer "F.Fab")
			(hide yes)
			(effects
				(font
					(size 1.016 1.016)
					(thickness 0.1524)
				)
			)
		)
		(property "Device Type" "C402H22"
			(at 1.1811 -4.2291 0)
			(unlocked yes)
			(layer "F.Fab")
			(hide yes)
			(effects
				(font
					(size 1.016 1.016)
					(thickness 0.1524)
				)
			)
		)
		(duplicate_pad_numbers_are_jumpers no)
		(fp_rect
			(start -0.4318 0.9525)
			(end 0.4318 -0.9525)
			(stroke
				(width 0)
				(type default)
			)
			(fill no)
			(layer "F.CrtYd")
		)
		(fp_rect
			(start -0.4318 0.9525)
			(end 0.4318 -0.9525)
			(stroke
				(width 0)
				(type default)
			)
			(fill no)
			(layer "F.Fab")
		)
		(pad "1" smd custom
			(at 0 -0.4445)
			(size 0.1524 0.1524)
			(layers "F.Cu" "F.Mask" "F.Paste")
			(net "HDD_PRSNT_34")
			(options
				(clearance outline)
				(anchor circle)
			)
			(primitives
				(gr_poly
					(pts
						(arc
							(start 0.3048 -0.2032)
							(mid 0.275042 -0.275042)
							(end 0.2032 -0.3048)
						)
						(arc
							(start -0.2032 -0.3048)
							(mid -0.275042 -0.275042)
							(end -0.3048 -0.2032)
						)
						(arc
							(start -0.3048 0.2032)
							(mid -0.275042 0.275042)
							(end -0.2032 0.3048)
						)
						(arc
							(start 0.2032 0.3048)
							(mid 0.275042 0.275042)
							(end 0.3048 0.2032)
						)
					)
					(width 0)
					(fill yes)
				)
			)
		)
		(pad "2" smd custom
			(at 0 0.4445)
			(size 0.1524 0.1524)
			(layers "F.Cu" "F.Mask" "F.Paste")
			(net "GND")
			(options
				(clearance outline)
				(anchor circle)
			)
			(primitives
				(gr_poly
					(pts
						(arc
							(start 0.3048 -0.2032)
							(mid 0.275042 -0.275042)
							(end 0.2032 -0.3048)
						)
						(arc
							(start -0.2032 -0.3048)
							(mid -0.275042 -0.275042)
							(end -0.3048 -0.2032)
						)
						(arc
							(start -0.3048 0.2032)
							(mid -0.275042 0.275042)
							(end -0.2032 0.3048)
						)
						(arc
							(start 0.2032 0.3048)
							(mid 0.275042 0.275042)
							(end 0.3048 0.2032)
						)
					)
					(width 0)
					(fill yes)
				)
			)
		)
	)
)
